# T6G (Grand Teton) — schematic netlist excerpt (pin names and nets, part order shuffled) for the footprints in the layout excerpt that follows; sources: Cadence DE-HDL packaged netlist, KiCad conversion of 04192023_DAF0TMB3IC0_F0TG_MB_C_brd_V02_OCP.brd

C9051  Q_CAP  0.1UF 25V 10% X7R  pkg 0402  page 142 : A = P3V3_AUX ; B = GND
C1531  Q_CAP_DIFFBUS  DIFF BUS_0.22UF 6.3V 20% X6S  pkg C0201  page 67 : \1\ = P5E_CPU1_P3_TX_C_DP<8> ; \2\ = P5E_CPU1_P3_TX_DP<8>
R4196  Q_RES  1K 1% EMPTY  pkg 0402LF  page 235 : A = P3V3_AUX ; B = U271_1_ADD1

(kicad_pcb
	(version 20260206)
	(generator "pcbnew")
	(generator_version "10.0")
	(general
		(thickness 1.6)
		(legacy_teardrops no)
	)
	(paper "A4")
	(title_block
		(title "04192023_DAF0TMB3IC0_F0TG_MB_C_brd_V02_OCP.brd")
		(comment 1 "Grand Teton / footprints 2650-2652 of 8354")
	)
	(layers
		(0 "F.Cu" signal "TOP")
		(4 "In1.Cu" signal "GND")
		(6 "In2.Cu" signal "IN1")
		(8 "In3.Cu" signal "GND1")
		(10 "In4.Cu" signal "IN2")
		(12 "In5.Cu" signal "GND2")
		(14 "In6.Cu" signal "IN3")
		(16 "In7.Cu" signal "GND3")
		(18 "In8.Cu" signal "VCC")
		(20 "In9.Cu" signal "VCC1")
		(22 "In10.Cu" signal "GND4")
		(24 "In11.Cu" signal "IN4")
		(26 "In12.Cu" signal "GND5")
		(28 "In13.Cu" signal "IN5")
		(30 "In14.Cu" signal "GND6")
		(32 "In15.Cu" signal "IN6")
		(34 "In16.Cu" signal "GND7")
		(2 "B.Cu" signal "BOTTOM")
		(9 "F.Adhes" user "F.Adhesive")
		(11 "B.Adhes" user "B.Adhesive")
		(13 "F.Paste" user "Package Geometry/Pastemask Top")
		(15 "B.Paste" user "Package Geometry/Pastemask Bottom")
		(5 "F.SilkS" user "Ref Des/Silkscreen Top")
		(7 "B.SilkS" user "Ref Des/Silkscreen Bottom")
		(1 "F.Mask" user "Board Geometry/Soldermask Top")
		(3 "B.Mask" user "Board Geometry/Soldermask Bottom")
		(17 "Dwgs.User" user "User.Drawings")
		(19 "Cmts.User" user "User.Comments")
		(21 "Eco1.User" user "User.Eco1")
		(23 "Eco2.User" user "User.Eco2")
		(25 "Edge.Cuts" user "Board Geometry/Outline")
		(27 "Margin" user)
		(31 "F.CrtYd" user "Package Geometry/Place Bound Top")
		(29 "B.CrtYd" user "Package Geometry/Place Bound Bottom")
		(35 "F.Fab" user "Ref Des/Assembly Top")
		(33 "B.Fab" user "Ref Des/Assembly Bottom")
	)
	(footprint ""
		(layer "F.Cu")
		(at 64.83858 -54.22138 -90)
		(property "Reference" "C9051"
			(at 0 0 270)
			(layer "F.SilkS")
			(hide yes)
			(effects
				(font
					(size 1.27 1.27)
				)
			)
		)
		(property "Value" ""
			(at 0 0 270)
			(layer "F.Fab")
			(effects
				(font
					(size 1.27 1.27)
				)
			)
		)
		(duplicate_pad_numbers_are_jumpers no)
		(fp_line
			(start -0.7874 0.4064)
			(end -0.7874 -0.4064)
			(stroke
				(width 0.1524)
				(type default)
			)
			(layer "F.SilkS")
		)
		(fp_line
			(start 0.7874 0.4064)
			(end -0.7874 0.4064)
			(stroke
				(width 0.1524)
				(type default)
			)
			(layer "F.SilkS")
		)
		(fp_line
			(start -0.7874 -0.4064)
			(end 0.7874 -0.4064)
			(stroke
				(width 0.1524)
				(type default)
			)
			(layer "F.SilkS")
		)
		(fp_line
			(start 0.7874 -0.4064)
			(end 0.7874 0.4064)
			(stroke
				(width 0.1524)
				(type default)
			)
			(layer "F.SilkS")
		)
		(fp_line
			(start -0.67945 0.3048)
			(end -0.67945 -0.305054)
			(stroke
				(width 0.1)
				(type default)
			)
			(layer "F.Fab")
		)
		(fp_line
			(start -0.12065 0.3048)
			(end -0.67945 0.3048)
			(stroke
				(width 0.1)
				(type default)
			)
			(layer "F.Fab")
		)
		(fp_line
			(start 0.120396 0.3048)
			(end 0.120396 0.2794)
			(stroke
				(width 0.1)
				(type default)
			)
			(layer "F.Fab")
		)
		(fp_line
			(start 0.67945 0.3048)
			(end 0.120396 0.3048)
			(stroke
				(width 0.1)
				(type default)
			)
			(layer "F.Fab")
		)
		(fp_line
			(start -0.12065 0.2794)
			(end -0.12065 0.3048)
			(stroke
				(width 0.1)
				(type default)
			)
			(layer "F.Fab")
		)
		(fp_line
			(start 0.120396 0.2794)
			(end -0.12065 0.2794)
			(stroke
				(width 0.1)
				(type default)
			)
			(layer "F.Fab")
		)
		(fp_line
			(start -0.12065 -0.2794)
			(end 0.12065 -0.2794)
			(stroke
				(width 0.1)
				(type default)
			)
			(layer "F.Fab")
		)
		(fp_line
			(start 0.12065 -0.2794)
			(end 0.12065 -0.3048)
			(stroke
				(width 0.1)
				(type default)
			)
			(layer "F.Fab")
		)
		(fp_line
			(start 0.12065 -0.3048)
			(end 0.67945 -0.3048)
			(stroke
				(width 0.1)
				(type default)
			)
			(layer "F.Fab")
		)
		(fp_line
			(start 0.67945 -0.3048)
			(end 0.67945 0.3048)
			(stroke
				(width 0.1)
				(type default)
			)
			(layer "F.Fab")
		)
		(fp_line
			(start -0.67945 -0.305054)
			(end -0.12065 -0.305054)
			(stroke
				(width 0.1)
				(type default)
			)
			(layer "F.Fab")
		)
		(fp_line
			(start -0.12065 -0.305054)
			(end -0.12065 -0.2794)
			(stroke
				(width 0.1)
				(type default)
			)
			(layer "F.Fab")
		)
		(pad "1" smd circle
			(at -0.40005 0 270)
			(size 0 0)
			(layers "F.Cu" "F.Mask" "F.Paste")
			(net "P3V3_AUX")
		)
		(pad "2" smd circle
			(at 0.40005 0 270)
			(size 0 0)
			(layers "F.Cu" "F.Mask" "F.Paste")
			(net "GND")
		)
	)
	(footprint ""
		(layer "F.Cu")
		(at 299.767498 -14.48181 180)
		(property "Reference" "R4196"
			(at 0 0 180)
			(layer "F.SilkS")
			(hide yes)
			(effects
				(font
					(size 1.27 1.27)
				)
			)
		)
		(property "Value" ""
			(at 0 0 180)
			(layer "F.Fab")
			(effects
				(font
					(size 1.27 1.27)
				)
			)
		)
		(duplicate_pad_numbers_are_jumpers no)
		(fp_line
			(start 0.7874 0.4064)
			(end -0.7874 0.4064)
			(stroke
				(width 0.1524)
				(type default)
			)
			(layer "F.SilkS")
		)
		(fp_line
			(start 0.7874 -0.4064)
			(end 0.7874 0.4064)
			(stroke
				(width 0.1524)
				(type default)
			)
			(layer "F.SilkS")
		)
		(fp_line
			(start -0.7874 0.4064)
			(end -0.7874 -0.4064)
			(stroke
				(width 0.1524)
				(type default)
			)
			(layer "F.SilkS")
		)
		(fp_line
			(start -0.7874 -0.4064)
			(end 0.7874 -0.4064)
			(stroke
				(width 0.1524)
				(type default)
			)
			(layer "F.SilkS")
		)
		(fp_line
			(start 0.67945 0.3048)
			(end 0.120396 0.3048)
			(stroke
				(width 0.1)
				(type default)
			)
			(layer "F.Fab")
		)
		(fp_line
			(start 0.67945 -0.3048)
			(end 0.67945 0.3048)
			(stroke
				(width 0.1)
				(type default)
			)
			(layer "F.Fab")
		)
		(fp_line
			(start 0.12065 -0.2794)
			(end 0.12065 -0.3048)
			(stroke
				(width 0.1)
				(type default)
			)
			(layer "F.Fab")
		)
		(fp_line
			(start 0.12065 -0.3048)
			(end 0.67945 -0.3048)
			(stroke
				(width 0.1)
				(type default)
			)
			(layer "F.Fab")
		)
		(fp_line
			(start 0.120396 0.3048)
			(end 0.120396 0.2794)
			(stroke
				(width 0.1)
				(type default)
			)
			(layer "F.Fab")
		)
		(fp_line
			(start 0.120396 0.2794)
			(end -0.12065 0.2794)
			(stroke
				(width 0.1)
				(type default)
			)
			(layer "F.Fab")
		)
		(fp_line
			(start -0.12065 0.3048)
			(end -0.67945 0.3048)
			(stroke
				(width 0.1)
				(type default)
			)
			(layer "F.Fab")
		)
		(fp_line
			(start -0.12065 0.2794)
			(end -0.12065 0.3048)
			(stroke
				(width 0.1)
				(type default)
			)
			(layer "F.Fab")
		)
		(fp_line
			(start -0.12065 -0.2794)
			(end 0.12065 -0.2794)
			(stroke
				(width 0.1)
				(type default)
			)
			(layer "F.Fab")
		)
		(fp_line
			(start -0.12065 -0.305054)
			(end -0.12065 -0.2794)
			(stroke
				(width 0.1)
				(type default)
			)
			(layer "F.Fab")
		)
		(fp_line
			(start -0.67945 0.3048)
			(end -0.67945 -0.305054)
			(stroke
				(width 0.1)
				(type default)
			)
			(layer "F.Fab")
		)
		(fp_line
			(start -0.67945 -0.305054)
			(end -0.12065 -0.305054)
			(stroke
				(width 0.1)
				(type default)
			)
			(layer "F.Fab")
		)
		(pad "1" smd circle
			(at -0.40005 0 180)
			(size 0 0)
			(layers "F.Cu" "F.Mask" "F.Paste")
			(net "P3V3_AUX")
		)
		(pad "2" smd circle
			(at 0.40005 0 180)
			(size 0 0)
			(layers "F.Cu" "F.Mask" "F.Paste")
			(net "U271_1_ADD1")
		)
	)
	(footprint ""
		(layer "F.Cu")
		(at 123.704096 -373.03583 -90)
		(property "Reference" "C1531"
			(at 0 0 270)
			(layer "F.SilkS")
			(hide yes)
			(effects
				(font
					(size 1.27 1.27)
				)
			)
		)
		(property "Value" ""
			(at 0 0 270)
			(layer "F.Fab")
			(effects
				(font
					(size 1.27 1.27)
				)
			)
		)
		(duplicate_pad_numbers_are_jumpers no)
		(fp_line
			(start -0.299974 0.150114)
			(end -0.299974 -0.150114)
			(stroke
				(width 0.1)
				(type default)
			)
			(layer "F.Fab")
		)
		(fp_line
			(start 0.299974 0.150114)
			(end -0.299974 0.150114)
			(stroke
				(width 0.1)
				(type default)
			)
			(layer "F.Fab")
		)
		(fp_line
			(start -0.299974 -0.150114)
			(end 0.299974 -0.150114)
			(stroke
				(width 0.1)
				(type default)
			)
			(layer "F.Fab")
		)
		(fp_line
			(start 0.299974 -0.150114)
			(end 0.299974 0.150114)
			(stroke
				(width 0.1)
				(type default)
			)
			(layer "F.Fab")
		)
		(pad "1" smd rect
			(at -0.2667 0 270)
			(size 0.3048 0.381)
			(layers "F.Cu" "F.Mask" "F.Paste")
			(net "P5E_CPU1_P3_TX_C_DP<8>")
		)
		(pad "2" smd rect
			(at 0.2667 0 270)
			(size 0.3048 0.381)
			(layers "F.Cu" "F.Mask" "F.Paste")
			(net "P5E_CPU1_P3_TX_DP<8>")
		)
	)
)
